# T6G (Grand Teton) — schematic netlist excerpt (pin names and nets, part order shuffled) for the footprints in the layout excerpt that follows; sources: Cadence DE-HDL packaged netlist, KiCad conversion of 04192023_DAF0TMB3IC0_F0TG_MB_C_brd_V02_OCP.brd

C2484  Q_CAP  22UF 4V 20% X6S  pkg C0402  page 74 : A = PVDDIO_P1 ; B = GND

U222  74CBTLV3126PW  IC  pkg TSSOP14  page 138
  \1oe\  = FB_BMC_ISOLATE1
  \1a\  = NCSI_BMC_RXD1_R1
  \1b\  = NCSI_OCP_V3_2_RXD1
  \2oe\  = FB_BMC_ISOLATE1
  \2a\  = NCSI_BMC_RXD0_R1
  \2b\  = NCSI_OCP_V3_2_RXD0
  GND  = GND
  \3b\  = NCSI_OCP_V3_2_CRS_DV
  \3a\  = NCSI_BMC_CRS_DV_R1
  \3oe\  = FB_BMC_ISOLATE1
  \4b\  = OCP_V3_2_ISO1_RBT_ARB_IN
  \4a\  = OCP_V3_2_RBT_ARB_IN_R
  \4oe\  = FB_BMC_ISOLATE1
  VCC  = P3V3_AUX

(kicad_pcb
	(version 20260206)
	(generator "pcbnew")
	(generator_version "10.0")
	(general
		(thickness 1.6)
		(legacy_teardrops no)
	)
	(paper "A4")
	(title_block
		(title "04192023_DAF0TMB3IC0_F0TG_MB_C_brd_V02_OCP.brd")
		(comment 1 "Grand Teton / footprints 6525-6526 of 8354")
	)
	(layers
		(0 "F.Cu" signal "TOP")
		(4 "In1.Cu" signal "GND")
		(6 "In2.Cu" signal "IN1")
		(8 "In3.Cu" signal "GND1")
		(10 "In4.Cu" signal "IN2")
		(12 "In5.Cu" signal "GND2")
		(14 "In6.Cu" signal "IN3")
		(16 "In7.Cu" signal "GND3")
		(18 "In8.Cu" signal "VCC")
		(20 "In9.Cu" signal "VCC1")
		(22 "In10.Cu" signal "GND4")
		(24 "In11.Cu" signal "IN4")
		(26 "In12.Cu" signal "GND5")
		(28 "In13.Cu" signal "IN5")
		(30 "In14.Cu" signal "GND6")
		(32 "In15.Cu" signal "IN6")
		(34 "In16.Cu" signal "GND7")
		(2 "B.Cu" signal "BOTTOM")
		(9 "F.Adhes" user "F.Adhesive")
		(11 "B.Adhes" user "B.Adhesive")
		(13 "F.Paste" user "Package Geometry/Pastemask Top")
		(15 "B.Paste" user "Package Geometry/Pastemask Bottom")
		(5 "F.SilkS" user "Ref Des/Silkscreen Top")
		(7 "B.SilkS" user "Ref Des/Silkscreen Bottom")
		(1 "F.Mask" user "Board Geometry/Soldermask Top")
		(3 "B.Mask" user "Board Geometry/Soldermask Bottom")
		(17 "Dwgs.User" user "User.Drawings")
		(19 "Cmts.User" user "User.Comments")
		(21 "Eco1.User" user "User.Eco1")
		(23 "Eco2.User" user "User.Eco2")
		(25 "Edge.Cuts" user "Board Geometry/Outline")
		(27 "Margin" user)
		(31 "F.CrtYd" user "Package Geometry/Place Bound Top")
		(29 "B.CrtYd" user "Package Geometry/Place Bound Bottom")
		(35 "F.Fab" user "Ref Des/Assembly Top")
		(33 "B.Fab" user "Ref Des/Assembly Bottom")
	)
	(footprint ""
		(layer "B.Cu")
		(at 102.378764 -258.830318 180)
		(property "Reference" "C2484"
			(at 0 0 0)
			(layer "B.SilkS")
			(hide yes)
			(effects
				(font
					(size 1.27 1.27)
				)
				(justify mirror)
			)
		)
		(property "Value" ""
			(at 0 0 0)
			(layer "B.Fab")
			(effects
				(font
					(size 1.27 1.27)
				)
				(justify mirror)
			)
		)
		(duplicate_pad_numbers_are_jumpers no)
		(fp_line
			(start 0.7874 0.4064)
			(end 0.7874 -0.4064)
			(stroke
				(width 0.1524)
				(type default)
			)
			(layer "B.SilkS")
		)
		(fp_line
			(start 0.7874 -0.4064)
			(end -0.7874 -0.4064)
			(stroke
				(width 0.1524)
				(type default)
			)
			(layer "B.SilkS")
		)
		(fp_line
			(start -0.7874 0.4064)
			(end 0.7874 0.4064)
			(stroke
				(width 0.1524)
				(type default)
			)
			(layer "B.SilkS")
		)
		(fp_line
			(start -0.7874 -0.4064)
			(end -0.7874 0.4064)
			(stroke
				(width 0.1524)
				(type default)
			)
			(layer "B.SilkS")
		)
		(fp_line
			(start 0.67945 0.3048)
			(end 0.67945 -0.305054)
			(stroke
				(width 0.1)
				(type default)
			)
			(layer "B.Fab")
		)
		(fp_line
			(start 0.67945 -0.305054)
			(end 0.12065 -0.305054)
			(stroke
				(width 0.1)
				(type default)
			)
			(layer "B.Fab")
		)
		(fp_line
			(start 0.12065 0.3048)
			(end 0.67945 0.3048)
			(stroke
				(width 0.1)
				(type default)
			)
			(layer "B.Fab")
		)
		(fp_line
			(start 0.12065 0.2794)
			(end 0.12065 0.3048)
			(stroke
				(width 0.1)
				(type default)
			)
			(layer "B.Fab")
		)
		(fp_line
			(start 0.12065 -0.2794)
			(end -0.12065 -0.2794)
			(stroke
				(width 0.1)
				(type default)
			)
			(layer "B.Fab")
		)
		(fp_line
			(start 0.12065 -0.305054)
			(end 0.12065 -0.2794)
			(stroke
				(width 0.1)
				(type default)
			)
			(layer "B.Fab")
		)
		(fp_line
			(start -0.120396 0.3048)
			(end -0.120396 0.2794)
			(stroke
				(width 0.1)
				(type default)
			)
			(layer "B.Fab")
		)
		(fp_line
			(start -0.120396 0.2794)
			(end 0.12065 0.2794)
			(stroke
				(width 0.1)
				(type default)
			)
			(layer "B.Fab")
		)
		(fp_line
			(start -0.12065 -0.2794)
			(end -0.12065 -0.3048)
			(stroke
				(width 0.1)
				(type default)
			)
			(layer "B.Fab")
		)
		(fp_line
			(start -0.12065 -0.3048)
			(end -0.67945 -0.3048)
			(stroke
				(width 0.1)
				(type default)
			)
			(layer "B.Fab")
		)
		(fp_line
			(start -0.67945 0.3048)
			(end -0.120396 0.3048)
			(stroke
				(width 0.1)
				(type default)
			)
			(layer "B.Fab")
		)
		(fp_line
			(start -0.67945 -0.3048)
			(end -0.67945 0.3048)
			(stroke
				(width 0.1)
				(type default)
			)
			(layer "B.Fab")
		)
		(pad "1" smd circle
			(at 0.40005 0)
			(size 0 0)
			(layers "B.Cu" "B.Mask" "B.Paste")
			(net "PVDDIO_P1")
		)
		(pad "2" smd circle
			(at -0.40005 0)
			(size 0 0)
			(layers "B.Cu" "B.Mask" "B.Paste")
			(net "GND")
		)
	)
	(footprint ""
		(layer "B.Cu")
		(at 209.295746 -77.263752)
		(property "Reference" "U222"
			(at 2.032 -3.27533 0)
			(unlocked yes)
			(layer "B.SilkS")
			(effects
				(font
					(size 0.7874 0.5842)
					(thickness 0.1524)
				)
				(justify left mirror)
			)
		)
		(property "Value" ""
			(at 0 0 0)
			(layer "B.Fab")
			(effects
				(font
					(size 1.27 1.27)
				)
				(justify mirror)
			)
		)
		(duplicate_pad_numbers_are_jumpers no)
		(fp_line
			(start -2.0066 -2.5527)
			(end -2.0066 2.5527)
			(stroke
				(width 0.1524)
				(type default)
			)
			(layer "B.SilkS")
		)
		(fp_line
			(start -2.0066 2.5527)
			(end 2.0066 2.5527)
			(stroke
				(width 0.1524)
				(type default)
			)
			(layer "B.SilkS")
		)
		(fp_line
			(start -0.5715 -2.5527)
			(end -2.0066 -2.5527)
			(stroke
				(width 0.1524)
				(type default)
			)
			(layer "B.SilkS")
		)
		(fp_line
			(start 0 -1.9812)
			(end -0.5715 -2.5527)
			(stroke
				(width 0.1524)
				(type default)
			)
			(layer "B.SilkS")
		)
		(fp_line
			(start 0.5715 -2.5527)
			(end 0 -1.9812)
			(stroke
				(width 0.1524)
				(type default)
			)
			(layer "B.SilkS")
		)
		(fp_line
			(start 2.0066 -2.5527)
			(end 0.5715 -2.5527)
			(stroke
				(width 0.1524)
				(type default)
			)
			(layer "B.SilkS")
		)
		(fp_line
			(start 2.0066 2.5527)
			(end 2.0066 -2.5527)
			(stroke
				(width 0.1524)
				(type default)
			)
			(layer "B.SilkS")
		)
		(fp_poly
			(pts
				(xy 3.81 -1.905) (xy 4.36372 -2.233168) (xy 4.36372 -1.608328)
			)
			(stroke
				(width 0)
				(type default)
			)
			(fill yes)
			(layer "B.SilkS")
		)
		(fp_line
			(start -2.249932 -2.549906)
			(end -2.249932 2.549906)
			(stroke
				(width 0.1)
				(type default)
			)
			(layer "B.Fab")
		)
		(fp_line
			(start -2.249932 2.549906)
			(end 2.249932 2.549906)
			(stroke
				(width 0.1)
				(type default)
			)
			(layer "B.Fab")
		)
		(fp_line
			(start 2.249932 -2.549906)
			(end -2.249932 -2.549906)
			(stroke
				(width 0.1)
				(type default)
			)
			(layer "B.Fab")
		)
		(fp_line
			(start 2.249932 2.549906)
			(end 2.249932 -2.549906)
			(stroke
				(width 0.1)
				(type default)
			)
			(layer "B.Fab")
		)
		(fp_poly
			(pts
				(xy 4.36372 -1.608328) (xy 4.36372 -2.233168) (xy 3.81 -1.905)
			)
			(stroke
				(width 0)
				(type default)
			)
			(fill yes)
			(layer "B.Fab")
		)
		(pad "1" smd rect
			(at 2.921 -1.949958 270)
			(size 0.3556 1.4986)
			(layers "B.Cu" "B.Mask" "B.Paste")
			(net "FB_BMC_ISOLATE1")
		)
		(pad "2" smd rect
			(at 2.921 -1.299972 270)
			(size 0.3556 1.4986)
			(layers "B.Cu" "B.Mask" "B.Paste")
			(net "NCSI_BMC_RXD1_R1")
		)
		(pad "3" smd rect
			(at 2.921 -0.649986 270)
			(size 0.3556 1.4986)
			(layers "B.Cu" "B.Mask" "B.Paste")
			(net "NCSI_OCP_V3_2_RXD1")
		)
		(pad "4" smd rect
			(at 2.921 0 270)
			(size 0.3556 1.4986)
			(layers "B.Cu" "B.Mask" "B.Paste")
			(net "FB_BMC_ISOLATE1")
		)
		(pad "5" smd rect
			(at 2.921 0.649986 270)
			(size 0.3556 1.4986)
			(layers "B.Cu" "B.Mask" "B.Paste")
			(net "NCSI_BMC_RXD0_R1")
		)
		(pad "6" smd rect
			(at 2.921 1.299972 270)
			(size 0.3556 1.4986)
			(layers "B.Cu" "B.Mask" "B.Paste")
			(net "NCSI_OCP_V3_2_RXD0")
		)
		(pad "7" smd rect
			(at 2.921 1.949958 270)
			(size 0.3556 1.4986)
			(layers "B.Cu" "B.Mask" "B.Paste")
			(net "GND")
		)
		(pad "8" smd rect
			(at -2.921 1.949958 270)
			(size 0.3556 1.4986)
			(layers "B.Cu" "B.Mask" "B.Paste")
			(net "NCSI_OCP_V3_2_CRS_DV")
		)
		(pad "9" smd rect
			(at -2.921 1.299972 270)
			(size 0.3556 1.4986)
			(layers "B.Cu" "B.Mask" "B.Paste")
			(net "NCSI_BMC_CRS_DV_R1")
		)
		(pad "10" smd rect
			(at -2.921 0.649986 270)
			(size 0.3556 1.4986)
			(layers "B.Cu" "B.Mask" "B.Paste")
			(net "FB_BMC_ISOLATE1")
		)
		(pad "11" smd rect
			(at -2.921 0 270)
			(size 0.3556 1.4986)
			(layers "B.Cu" "B.Mask" "B.Paste")
			(net "OCP_V3_2_ISO1_RBT_ARB_IN")
		)
		(pad "12" smd rect
			(at -2.921 -0.649986 270)
			(size 0.3556 1.4986)
			(layers "B.Cu" "B.Mask" "B.Paste")
			(net "OCP_V3_2_RBT_ARB_IN_R")
		)
		(pad "13" smd rect
			(at -2.921 -1.299972 270)
			(size 0.3556 1.4986)
			(layers "B.Cu" "B.Mask" "B.Paste")
			(net "FB_BMC_ISOLATE1")
		)
		(pad "14" smd rect
			(at -2.921 -1.949958 270)
			(size 0.3556 1.4986)
			(layers "B.Cu" "B.Mask" "B.Paste")
			(net "P3V3_AUX")
		)
	)
)
